(kicad_pcb
	(version 20260206)
	(generator "pcbnew")
	(generator_version "10.0")
	(general
		(thickness 1.6)
		(legacy_teardrops no)
	)
	(paper "A4")
	(title_block
		(title "04192023_DAF0TMB3IC0_F0TG_MB_C_brd_V02_OCP.brd")
		(comment 1 "Grand Teton / footprints 3930-3936 of 8354")
	)
	(layers
		(0 "F.Cu" signal "TOP")
		(4 "In1.Cu" signal "GND")
		(6 "In2.Cu" signal "IN1")
		(8 "In3.Cu" signal "GND1")
		(10 "In4.Cu" signal "IN2")
		(12 "In5.Cu" signal "GND2")
		(14 "In6.Cu" signal "IN3")
		(16 "In7.Cu" signal "GND3")
		(18 "In8.Cu" signal "VCC")
		(20 "In9.Cu" signal "VCC1")
		(22 "In10.Cu" signal "GND4")
		(24 "In11.Cu" signal "IN4")
		(26 "In12.Cu" signal "GND5")
		(28 "In13.Cu" signal "IN5")
		(30 "In14.Cu" signal "GND6")
		(32 "In15.Cu" signal "IN6")
		(34 "In16.Cu" signal "GND7")
		(2 "B.Cu" signal "BOTTOM")
		(9 "F.Adhes" user "F.Adhesive")
		(11 "B.Adhes" user "B.Adhesive")
		(13 "F.Paste" user "Package Geometry/Pastemask Top")
		(15 "B.Paste" user "Package Geometry/Pastemask Bottom")
		(5 "F.SilkS" user "Ref Des/Silkscreen Top")
		(7 "B.SilkS" user "Ref Des/Silkscreen Bottom")
		(1 "F.Mask" user "Board Geometry/Soldermask Top")
		(3 "B.Mask" user "Board Geometry/Soldermask Bottom")
		(17 "Dwgs.User" user "User.Drawings")
		(19 "Cmts.User" user "User.Comments")
		(21 "Eco1.User" user "User.Eco1")
		(23 "Eco2.User" user "User.Eco2")
		(25 "Edge.Cuts" user "Board Geometry/Outline")
		(27 "Margin" user)
		(31 "F.CrtYd" user "Package Geometry/Place Bound Top")
		(29 "B.CrtYd" user "Package Geometry/Place Bound Bottom")
		(35 "F.Fab" user "Ref Des/Assembly Top")
		(33 "B.Fab" user "Ref Des/Assembly Bottom")
	)
	(footprint ""
		(layer "F.Cu")
		(at 177.378106 -426.332396)
		(property "Reference" "R2695"
			(at 0 0 0)
			(layer "F.SilkS")
			(hide yes)
			(effects
				(font
					(size 1.27 1.27)
				)
			)
		)
		(property "Value" ""
			(at 0 0 0)
			(layer "F.Fab")
			(effects
				(font
					(size 1.27 1.27)
				)
			)
		)
		(duplicate_pad_numbers_are_jumpers no)
		(fp_line
			(start -0.7874 -0.4064)
			(end 0.7874 -0.4064)
			(stroke
				(width 0.1524)
				(type default)
			)
			(layer "F.SilkS")
		)
		(fp_line
			(start -0.7874 0.4064)
			(end -0.7874 -0.4064)
			(stroke
				(width 0.1524)
				(type default)
			)
			(layer "F.SilkS")
		)
		(fp_line
			(start 0.7874 -0.4064)
			(end 0.7874 0.4064)
			(stroke
				(width 0.1524)
				(type default)
			)
			(layer "F.SilkS")
		)
		(fp_line
			(start 0.7874 0.4064)
			(end -0.7874 0.4064)
			(stroke
				(width 0.1524)
				(type default)
			)
			(layer "F.SilkS")
		)
		(fp_line
			(start -0.67945 -0.305054)
			(end -0.12065 -0.305054)
			(stroke
				(width 0.1)
				(type default)
			)
			(layer "F.Fab")
		)
		(fp_line
			(start -0.67945 0.3048)
			(end -0.67945 -0.305054)
			(stroke
				(width 0.1)
				(type default)
			)
			(layer "F.Fab")
		)
		(fp_line
			(start -0.12065 -0.305054)
			(end -0.12065 -0.2794)
			(stroke
				(width 0.1)
				(type default)
			)
			(layer "F.Fab")
		)
		(fp_line
			(start -0.12065 -0.2794)
			(end 0.12065 -0.2794)
			(stroke
				(width 0.1)
				(type default)
			)
			(layer "F.Fab")
		)
		(fp_line
			(start -0.12065 0.2794)
			(end -0.12065 0.3048)
			(stroke
				(width 0.1)
				(type default)
			)
			(layer "F.Fab")
		)
		(fp_line
			(start -0.12065 0.3048)
			(end -0.67945 0.3048)
			(stroke
				(width 0.1)
				(type default)
			)
			(layer "F.Fab")
		)
		(fp_line
			(start 0.120396 0.2794)
			(end -0.12065 0.2794)
			(stroke
				(width 0.1)
				(type default)
			)
			(layer "F.Fab")
		)
		(fp_line
			(start 0.120396 0.3048)
			(end 0.120396 0.2794)
			(stroke
				(width 0.1)
				(type default)
			)
			(layer "F.Fab")
		)
		(fp_line
			(start 0.12065 -0.3048)
			(end 0.67945 -0.3048)
			(stroke
				(width 0.1)
				(type default)
			)
			(layer "F.Fab")
		)
		(fp_line
			(start 0.12065 -0.2794)
			(end 0.12065 -0.3048)
			(stroke
				(width 0.1)
				(type default)
			)
			(layer "F.Fab")
		)
		(fp_line
			(start 0.67945 -0.3048)
			(end 0.67945 0.3048)
			(stroke
				(width 0.1)
				(type default)
			)
			(layer "F.Fab")
		)
		(fp_line
			(start 0.67945 0.3048)
			(end 0.120396 0.3048)
			(stroke
				(width 0.1)
				(type default)
			)
			(layer "F.Fab")
		)
		(pad "1" smd circle
			(at -0.40005 0)
			(size 0 0)
			(layers "F.Cu" "F.Mask" "F.Paste")
			(net "P3V3_AUX")
		)
		(pad "2" smd circle
			(at 0.40005 0)
			(size 0 0)
			(layers "F.Cu" "F.Mask" "F.Paste")
			(net "TCA9539_0_ADD0")
		)
	)
	(footprint ""
		(layer "F.Cu")
		(at 59.497722 -181.819042 180)
		(property "Reference" "PR161"
			(at 0 0 180)
			(layer "F.SilkS")
			(hide yes)
			(effects
				(font
					(size 1.27 1.27)
				)
			)
		)
		(property "Value" ""
			(at 0 0 180)
			(layer "F.Fab")
			(effects
				(font
					(size 1.27 1.27)
				)
			)
		)
		(duplicate_pad_numbers_are_jumpers no)
		(fp_line
			(start 0.7874 0.4064)
			(end -0.7874 0.4064)
			(stroke
				(width 0.1524)
				(type default)
			)
			(layer "F.SilkS")
		)
		(fp_line
			(start 0.7874 -0.4064)
			(end 0.7874 0.4064)
			(stroke
				(width 0.1524)
				(type default)
			)
			(layer "F.SilkS")
		)
		(fp_line
			(start -0.7874 0.4064)
			(end -0.7874 -0.4064)
			(stroke
				(width 0.1524)
				(type default)
			)
			(layer "F.SilkS")
		)
		(fp_line
			(start -0.7874 -0.4064)
			(end 0.7874 -0.4064)
			(stroke
				(width 0.1524)
				(type default)
			)
			(layer "F.SilkS")
		)
		(fp_line
			(start 0.67945 0.3048)
			(end 0.120396 0.3048)
			(stroke
				(width 0.1)
				(type default)
			)
			(layer "F.Fab")
		)
		(fp_line
			(start 0.67945 -0.3048)
			(end 0.67945 0.3048)
			(stroke
				(width 0.1)
				(type default)
			)
			(layer "F.Fab")
		)
		(fp_line
			(start 0.12065 -0.2794)
			(end 0.12065 -0.3048)
			(stroke
				(width 0.1)
				(type default)
			)
			(layer "F.Fab")
		)
		(fp_line
			(start 0.12065 -0.3048)
			(end 0.67945 -0.3048)
			(stroke
				(width 0.1)
				(type default)
			)
			(layer "F.Fab")
		)
		(fp_line
			(start 0.120396 0.3048)
			(end 0.120396 0.2794)
			(stroke
				(width 0.1)
				(type default)
			)
			(layer "F.Fab")
		)
		(fp_line
			(start 0.120396 0.2794)
			(end -0.12065 0.2794)
			(stroke
				(width 0.1)
				(type default)
			)
			(layer "F.Fab")
		)
		(fp_line
			(start -0.12065 0.3048)
			(end -0.67945 0.3048)
			(stroke
				(width 0.1)
				(type default)
			)
			(layer "F.Fab")
		)
		(fp_line
			(start -0.12065 0.2794)
			(end -0.12065 0.3048)
			(stroke
				(width 0.1)
				(type default)
			)
			(layer "F.Fab")
		)
		(fp_line
			(start -0.12065 -0.2794)
			(end 0.12065 -0.2794)
			(stroke
				(width 0.1)
				(type default)
			)
			(layer "F.Fab")
		)
		(fp_line
			(start -0.12065 -0.305054)
			(end -0.12065 -0.2794)
			(stroke
				(width 0.1)
				(type default)
			)
			(layer "F.Fab")
		)
		(fp_line
			(start -0.67945 0.3048)
			(end -0.67945 -0.305054)
			(stroke
				(width 0.1)
				(type default)
			)
			(layer "F.Fab")
		)
		(fp_line
			(start -0.67945 -0.305054)
			(end -0.12065 -0.305054)
			(stroke
				(width 0.1)
				(type default)
			)
			(layer "F.Fab")
		)
		(pad "1" smd circle
			(at -0.40005 0 180)
			(size 0 0)
			(layers "F.Cu" "F.Mask" "F.Paste")
			(net "PVDDCR_CPU0_P1")
		)
		(pad "2" smd circle
			(at 0.40005 0 180)
			(size 0 0)
			(layers "F.Cu" "F.Mask" "F.Paste")
			(net "VSENSE_PVDDCR_CPU0_P1_DP")
		)
	)
	(footprint ""
		(layer "F.Cu")
		(at 28.71851 -337.403948)
		(property "Reference" "PL67"
			(at -3.242056 -15.887446 0)
			(unlocked yes)
			(layer "F.SilkS")
			(effects
				(font
					(size 0.7874 0.5842)
					(thickness 0.1524)
				)
				(justify left)
			)
		)
		(property "Value" ""
			(at 0 0 0)
			(layer "F.Fab")
			(effects
				(font
					(size 1.27 1.27)
				)
			)
		)
		(duplicate_pad_numbers_are_jumpers no)
		(fp_line
			(start -3.750056 -5.500116)
			(end -2.393442 -5.500116)
			(stroke
				(width 0.1524)
				(type default)
			)
			(layer "F.SilkS")
		)
		(fp_line
			(start -3.750056 5.500116)
			(end -3.750056 -5.500116)
			(stroke
				(width 0.1524)
				(type default)
			)
			(layer "F.SilkS")
		)
		(fp_line
			(start -2.393442 5.500116)
			(end -3.750056 5.500116)
			(stroke
				(width 0.1524)
				(type default)
			)
			(layer "F.SilkS")
		)
		(fp_line
			(start 2.393442 5.500116)
			(end 3.750056 5.500116)
			(stroke
				(width 0.1524)
				(type default)
			)
			(layer "F.SilkS")
		)
		(fp_line
			(start 3.750056 -5.500116)
			(end 2.393442 -5.500116)
			(stroke
				(width 0.1524)
				(type default)
			)
			(layer "F.SilkS")
		)
		(fp_line
			(start 3.750056 5.500116)
			(end 3.750056 -5.500116)
			(stroke
				(width 0.1524)
				(type default)
			)
			(layer "F.SilkS")
		)
		(fp_poly
			(pts
				(xy -3.9116 -4.249928) (xy -4.2164 -4.097528) (xy -4.2164 -4.402328)
			)
			(stroke
				(width 0)
				(type default)
			)
			(fill yes)
			(layer "F.SilkS")
		)
		(fp_line
			(start -3.750056 -5.500116)
			(end -3.750056 5.500116)
			(stroke
				(width 0.1)
				(type default)
			)
			(layer "F.Fab")
		)
		(fp_line
			(start -3.750056 5.500116)
			(end 3.750056 5.500116)
			(stroke
				(width 0.1)
				(type default)
			)
			(layer "F.Fab")
		)
		(fp_line
			(start 3.750056 -5.500116)
			(end -3.750056 -5.500116)
			(stroke
				(width 0.1)
				(type default)
			)
			(layer "F.Fab")
		)
		(fp_line
			(start 3.750056 5.500116)
			(end 3.750056 -5.500116)
			(stroke
				(width 0.1)
				(type default)
			)
			(layer "F.Fab")
		)
		(fp_poly
			(pts
				(xy -4.9276 -4.757928) (xy -4.9276 -3.741928) (xy -3.9116 -4.249928)
			)
			(stroke
				(width 0)
				(type default)
			)
			(fill yes)
			(layer "F.Fab")
		)
		(pad "1" smd rect
			(at 0 -4.249928 270)
			(size 2.413 4.5212)
			(layers "F.Cu" "F.Mask" "F.Paste")
			(net "SW_PVDDIO_P1_SW4")
		)
		(pad "2" smd rect
			(at 0 -1.175004 270)
			(size 1.3716 4.5212)
			(layers "F.Cu" "F.Mask" "F.Paste")
			(net "IND_PVDDIO_P1_CPL0")
		)
		(pad "3" smd rect
			(at 0 1.175004 270)
			(size 1.3716 4.5212)
			(layers "F.Cu" "F.Mask" "F.Paste")
			(net "IND_PVDDIO_P1_CPL4")
		)
		(pad "4" smd rect
			(at 0 4.249928 270)
			(size 2.413 4.5212)
			(layers "F.Cu" "F.Mask" "F.Paste")
			(net "PVDDIO_P1")
		)
	)
	(footprint ""
		(layer "F.Cu")
		(at 143.171672 -386.684774 -90)
		(property "Reference" "R637"
			(at 0 0 270)
			(layer "F.SilkS")
			(hide yes)
			(effects
				(font
					(size 1.27 1.27)
				)
			)
		)
		(property "Value" ""
			(at 0 0 270)
			(layer "F.Fab")
			(effects
				(font
					(size 1.27 1.27)
				)
			)
		)
		(duplicate_pad_numbers_are_jumpers no)
		(fp_line
			(start -0.32512 0.175006)
			(end -0.32512 -0.175006)
			(stroke
				(width 0.1)
				(type default)
			)
			(layer "F.Fab")
		)
		(fp_line
			(start 0.32512 0.175006)
			(end -0.32512 0.175006)
			(stroke
				(width 0.1)
				(type default)
			)
			(layer "F.Fab")
		)
		(fp_line
			(start -0.32512 -0.175006)
			(end 0.32512 -0.175006)
			(stroke
				(width 0.1)
				(type default)
			)
			(layer "F.Fab")
		)
		(fp_line
			(start 0.32512 -0.175006)
			(end 0.32512 0.175006)
			(stroke
				(width 0.1)
				(type default)
			)
			(layer "F.Fab")
		)
		(pad "1" smd rect
			(at -0.2667 0 270)
			(size 0.3048 0.381)
			(layers "F.Cu" "F.Mask" "F.Paste")
			(net "CLK_100M_RETIMER_CPU1_P2_DN")
		)
		(pad "2" smd rect
			(at 0.2667 0 90)
			(size 0.3048 0.381)
			(layers "F.Cu" "F.Mask" "F.Paste")
			(net "GND")
		)
	)
	(footprint ""
		(layer "F.Cu")
		(at 95.26143 -58.07583)
		(property "Reference" "PR3822"
			(at 0 0 0)
			(layer "F.SilkS")
			(hide yes)
			(effects
				(font
					(size 1.27 1.27)
				)
			)
		)
		(property "Value" ""
			(at 0 0 0)
			(layer "F.Fab")
			(effects
				(font
					(size 1.27 1.27)
				)
			)
		)
		(duplicate_pad_numbers_are_jumpers no)
		(fp_line
			(start -0.7874 -0.4064)
			(end 0.7874 -0.4064)
			(stroke
				(width 0.1524)
				(type default)
			)
			(layer "F.SilkS")
		)
		(fp_line
			(start -0.7874 0.4064)
			(end -0.7874 -0.4064)
			(stroke
				(width 0.1524)
				(type default)
			)
			(layer "F.SilkS")
		)
		(fp_line
			(start 0.7874 -0.4064)
			(end 0.7874 0.4064)
			(stroke
				(width 0.1524)
				(type default)
			)
			(layer "F.SilkS")
		)
		(fp_line
			(start 0.7874 0.4064)
			(end -0.7874 0.4064)
			(stroke
				(width 0.1524)
				(type default)
			)
			(layer "F.SilkS")
		)
		(fp_line
			(start -0.67945 -0.305054)
			(end -0.12065 -0.305054)
			(stroke
				(width 0.1)
				(type default)
			)
			(layer "F.Fab")
		)
		(fp_line
			(start -0.67945 0.3048)
			(end -0.67945 -0.305054)
			(stroke
				(width 0.1)
				(type default)
			)
			(layer "F.Fab")
		)
		(fp_line
			(start -0.12065 -0.305054)
			(end -0.12065 -0.2794)
			(stroke
				(width 0.1)
				(type default)
			)
			(layer "F.Fab")
		)
		(fp_line
			(start -0.12065 -0.2794)
			(end 0.12065 -0.2794)
			(stroke
				(width 0.1)
				(type default)
			)
			(layer "F.Fab")
		)
		(fp_line
			(start -0.12065 0.2794)
			(end -0.12065 0.3048)
			(stroke
				(width 0.1)
				(type default)
			)
			(layer "F.Fab")
		)
		(fp_line
			(start -0.12065 0.3048)
			(end -0.67945 0.3048)
			(stroke
				(width 0.1)
				(type default)
			)
			(layer "F.Fab")
		)
		(fp_line
			(start 0.120396 0.2794)
			(end -0.12065 0.2794)
			(stroke
				(width 0.1)
				(type default)
			)
			(layer "F.Fab")
		)
		(fp_line
			(start 0.120396 0.3048)
			(end 0.120396 0.2794)
			(stroke
				(width 0.1)
				(type default)
			)
			(layer "F.Fab")
		)
		(fp_line
			(start 0.12065 -0.3048)
			(end 0.67945 -0.3048)
			(stroke
				(width 0.1)
				(type default)
			)
			(layer "F.Fab")
		)
		(fp_line
			(start 0.12065 -0.2794)
			(end 0.12065 -0.3048)
			(stroke
				(width 0.1)
				(type default)
			)
			(layer "F.Fab")
		)
		(fp_line
			(start 0.67945 -0.3048)
			(end 0.67945 0.3048)
			(stroke
				(width 0.1)
				(type default)
			)
			(layer "F.Fab")
		)
		(fp_line
			(start 0.67945 0.3048)
			(end 0.120396 0.3048)
			(stroke
				(width 0.1)
				(type default)
			)
			(layer "F.Fab")
		)
		(pad "1" smd circle
			(at -0.40005 0)
			(size 0 0)
			(layers "F.Cu" "F.Mask" "F.Paste")
			(net "P3V3_OCP_CB_2")
		)
		(pad "2" smd circle
			(at 0.40005 0)
			(size 0 0)
			(layers "F.Cu" "F.Mask" "F.Paste")
			(net "GND")
		)
	)
	(footprint ""
		(layer "F.Cu")
		(at 398.595088 -385.23926 180)
		(property "Reference" "C866"
			(at 0 0 180)
			(layer "F.SilkS")
			(hide yes)
			(effects
				(font
					(size 1.27 1.27)
				)
			)
		)
		(property "Value" ""
			(at 0 0 180)
			(layer "F.Fab")
			(effects
				(font
					(size 1.27 1.27)
				)
			)
		)
		(duplicate_pad_numbers_are_jumpers no)
		(fp_line
			(start 0.299974 0.150114)
			(end -0.299974 0.150114)
			(stroke
				(width 0.1)
				(type default)
			)
			(layer "F.Fab")
		)
		(fp_line
			(start 0.299974 -0.150114)
			(end 0.299974 0.150114)
			(stroke
				(width 0.1)
				(type default)
			)
			(layer "F.Fab")
		)
		(fp_line
			(start -0.299974 0.150114)
			(end -0.299974 -0.150114)
			(stroke
				(width 0.1)
				(type default)
			)
			(layer "F.Fab")
		)
		(fp_line
			(start -0.299974 -0.150114)
			(end 0.299974 -0.150114)
			(stroke
				(width 0.1)
				(type default)
			)
			(layer "F.Fab")
		)
		(pad "1" smd rect
			(at -0.2667 0 180)
			(size 0.3048 0.381)
			(layers "F.Cu" "F.Mask" "F.Paste")
			(net "P5E_CPU0_P2_TX_C_DN<1>")
		)
		(pad "2" smd rect
			(at 0.2667 0 180)
			(size 0.3048 0.381)
			(layers "F.Cu" "F.Mask" "F.Paste")
			(net "P5E_CPU0_P2_TX_DN<1>")
		)
	)
	(footprint ""
		(layer "F.Cu")
		(at 126.571756 -29.697172 90)
		(property "Reference" "C93"
			(at 0 0 90)
			(layer "F.SilkS")
			(hide yes)
			(effects
				(font
					(size 1.27 1.27)
				)
			)
		)
		(property "Value" ""
			(at 0 0 90)
			(layer "F.Fab")
			(effects
				(font
					(size 1.27 1.27)
				)
			)
		)
		(duplicate_pad_numbers_are_jumpers no)
		(fp_line
			(start 0.7874 -0.4064)
			(end 0.7874 0.4064)
			(stroke
				(width 0.1524)
				(type default)
			)
			(layer "F.SilkS")
		)
		(fp_line
			(start -0.7874 -0.4064)
			(end 0.7874 -0.4064)
			(stroke
				(width 0.1524)
				(type default)
			)
			(layer "F.SilkS")
		)
		(fp_line
			(start 0.7874 0.4064)
			(end -0.7874 0.4064)
			(stroke
				(width 0.1524)
				(type default)
			)
			(layer "F.SilkS")
		)
		(fp_line
			(start -0.7874 0.4064)
			(end -0.7874 -0.4064)
			(stroke
				(width 0.1524)
				(type default)
			)
			(layer "F.SilkS")
		)
		(fp_line
			(start -0.12065 -0.305054)
			(end -0.12065 -0.2794)
			(stroke
				(width 0.1)
				(type default)
			)
			(layer "F.Fab")
		)
		(fp_line
			(start -0.67945 -0.305054)
			(end -0.12065 -0.305054)
			(stroke
				(width 0.1)
				(type default)
			)
			(layer "F.Fab")
		)
		(fp_line
			(start 0.67945 -0.3048)
			(end 0.67945 0.3048)
			(stroke
				(width 0.1)
				(type default)
			)
			(layer "F.Fab")
		)
		(fp_line
			(start 0.12065 -0.3048)
			(end 0.67945 -0.3048)
			(stroke
				(width 0.1)
				(type default)
			)
			(layer "F.Fab")
		)
		(fp_line
			(start 0.12065 -0.2794)
			(end 0.12065 -0.3048)
			(stroke
				(width 0.1)
				(type default)
			)
			(layer "F.Fab")
		)
		(fp_line
			(start -0.12065 -0.2794)
			(end 0.12065 -0.2794)
			(stroke
				(width 0.1)
				(type default)
			)
			(layer "F.Fab")
		)
		(fp_line
			(start 0.120396 0.2794)
			(end -0.12065 0.2794)
			(stroke
				(width 0.1)
				(type default)
			)
			(layer "F.Fab")
		)
		(fp_line
			(start -0.12065 0.2794)
			(end -0.12065 0.3048)
			(stroke
				(width 0.1)
				(type default)
			)
			(layer "F.Fab")
		)
		(fp_line
			(start 0.67945 0.3048)
			(end 0.120396 0.3048)
			(stroke
				(width 0.1)
				(type default)
			)
			(layer "F.Fab")
		)
		(fp_line
			(start 0.120396 0.3048)
			(end 0.120396 0.2794)
			(stroke
				(width 0.1)
				(type default)
			)
			(layer "F.Fab")
		)
		(fp_line
			(start -0.12065 0.3048)
			(end -0.67945 0.3048)
			(stroke
				(width 0.1)
				(type default)
			)
			(layer "F.Fab")
		)
		(fp_line
			(start -0.67945 0.3048)
			(end -0.67945 -0.305054)
			(stroke
				(width 0.1)
				(type default)
			)
			(layer "F.Fab")
		)
		(pad "1" smd circle
			(at -0.40005 0 90)
			(size 0 0)
			(layers "F.Cu" "F.Mask" "F.Paste")
			(net "XTAL_USB_CPU0_HUB1_XOUT")
		)
		(pad "2" smd circle
			(at 0.40005 0 90)
			(size 0 0)
			(layers "F.Cu" "F.Mask" "F.Paste")
			(net "GND")
		)
	)
)
